(kicad_pcb
	(version 20260206)
	(generator "pcbnew")
	(generator_version "10.0")
	(general
		(thickness 1.6)
		(legacy_teardrops no)
	)
	(paper "A4")
	(title_block
		(title "dpb — 14545-sa.0730WZS0815.brd")
		(comment 1 "Honey Badger (Wiwynn) / footprints 26-33 of 1066")
	)
	(layers
		(0 "F.Cu" signal "TOP")
		(4 "In1.Cu" signal "L2GND")
		(6 "In2.Cu" signal "L3")
		(8 "In3.Cu" signal "L4VCC")
		(10 "In4.Cu" signal "L5VCC")
		(12 "In5.Cu" signal "L6")
		(14 "In6.Cu" signal "L7GND")
		(2 "B.Cu" signal "BOTTOM")
		(9 "F.Adhes" user "F.Adhesive")
		(11 "B.Adhes" user "B.Adhesive")
		(13 "F.Paste" user "Package Geometry/Pastemask Top")
		(15 "B.Paste" user "Package Geometry/Pastemask Bottom")
		(5 "F.SilkS" user "Ref Des/Silkscreen Top")
		(7 "B.SilkS" user "Ref Des/Silkscreen Bottom")
		(1 "F.Mask" user "Board Geometry/Soldermask Top")
		(3 "B.Mask" user "Board Geometry/Soldermask Bottom")
		(17 "Dwgs.User" user "User.Drawings")
		(19 "Cmts.User" user "User.Comments")
		(21 "Eco1.User" user "User.Eco1")
		(23 "Eco2.User" user "User.Eco2")
		(25 "Edge.Cuts" user "Board Geometry/Outline")
		(27 "Margin" user)
		(31 "F.CrtYd" user "Package Geometry/Place Bound Top")
		(29 "B.CrtYd" user "Package Geometry/Place Bound Bottom")
		(35 "F.Fab" user "Ref Des/Assembly Top")
		(33 "B.Fab" user "Ref Des/Assembly Bottom")
	)
	(footprint ""
		(layer "F.Cu")
		(at 5.102098 -501.6373 180)
		(property "Reference" "PG3"
			(at 0 0 180)
			(layer "F.SilkS")
			(hide yes)
			(effects
				(font
					(size 1.27 1.27)
				)
			)
		)
		(property "Value" "COPPER-CLOSE-GP-U"
			(at 0.0762 -2.8702 180)
			(unlocked yes)
			(layer "F.Fab")
			(hide yes)
			(effects
				(font
					(size 1.016 1.016)
					(thickness 0.1524)
				)
			)
		)
		(property "Device Type" "CON2C-U"
			(at 0.0762 -4.3942 180)
			(unlocked yes)
			(layer "F.Fab")
			(hide yes)
			(effects
				(font
					(size 1.016 1.016)
					(thickness 0.1524)
				)
			)
		)
		(duplicate_pad_numbers_are_jumpers no)
		(fp_rect
			(start -0.9398 0.9652)
			(end 0.9398 -0.9652)
			(stroke
				(width 0)
				(type default)
			)
			(fill no)
			(layer "F.CrtYd")
		)
		(fp_rect
			(start -0.9398 0.9652)
			(end 0.9398 -0.9652)
			(stroke
				(width 0)
				(type default)
			)
			(fill no)
			(layer "F.Fab")
		)
		(pad "1" smd custom
			(at 0 -0.5334 180)
			(size 0.17145 0.17145)
			(layers "F.Cu" "F.Mask" "F.Paste")
			(net "P5VC_AGND")
			(options
				(clearance outline)
				(anchor circle)
			)
			(primitives
				(gr_poly
					(pts
						(xy -0.127 0.3429) (xy -0.127 0.1651) (xy -0.635 -0.3429) (xy 0.635 -0.3429) (xy 0.127 0.1651)
						(xy 0.127 0.3429)
					)
					(width 0)
					(fill yes)
				)
			)
		)
		(pad "2" smd custom
			(at 0 0.5334 180)
			(size 0.17145 0.17145)
			(layers "F.Cu" "F.Mask" "F.Paste")
			(net "GND")
			(options
				(clearance outline)
				(anchor circle)
			)
			(primitives
				(gr_poly
					(pts
						(xy -0.635 0.3429) (xy -0.127 -0.1651) (xy -0.127 -0.3429) (xy 0.127 -0.3429) (xy 0.127 -0.1651)
						(xy 0.635 0.3429)
					)
					(width 0)
					(fill yes)
				)
			)
		)
	)
	(footprint ""
		(layer "F.Cu")
		(at 213.4616 -497.713 180)
		(property "Reference" "C111"
			(at 0 0 180)
			(layer "F.SilkS")
			(hide yes)
			(effects
				(font
					(size 1.27 1.27)
				)
			)
		)
		(property "Value" "SC10U25V6KX-1GP"
			(at -0.0762 -5.1308 180)
			(unlocked yes)
			(layer "F.Fab")
			(hide yes)
			(effects
				(font
					(size 1.016 1.016)
					(thickness 0.1524)
				)
			)
		)
		(property "Device Type" "C1206H71"
			(at -0.127 -6.6548 180)
			(unlocked yes)
			(layer "F.Fab")
			(hide yes)
			(effects
				(font
					(size 1.016 1.016)
					(thickness 0.1524)
				)
			)
		)
		(duplicate_pad_numbers_are_jumpers no)
		(fp_line
			(start 1.016 2.2352)
			(end -1.016 2.2352)
			(stroke
				(width 0.1524)
				(type default)
			)
			(layer "F.SilkS")
		)
		(fp_line
			(start 1.016 0.8382)
			(end 1.016 2.2352)
			(stroke
				(width 0.1524)
				(type default)
			)
			(layer "F.SilkS")
		)
		(fp_line
			(start 1.016 -2.2352)
			(end 1.016 -0.8382)
			(stroke
				(width 0.1524)
				(type default)
			)
			(layer "F.SilkS")
		)
		(fp_line
			(start -1.016 2.2352)
			(end -1.016 0.8382)
			(stroke
				(width 0.1524)
				(type default)
			)
			(layer "F.SilkS")
		)
		(fp_line
			(start -1.016 -0.8382)
			(end -1.016 -2.2352)
			(stroke
				(width 0.1524)
				(type default)
			)
			(layer "F.SilkS")
		)
		(fp_line
			(start -1.016 -2.2352)
			(end 1.016 -2.2352)
			(stroke
				(width 0.1524)
				(type default)
			)
			(layer "F.SilkS")
		)
		(fp_rect
			(start -1.0922 2.3114)
			(end 1.0922 -2.3114)
			(stroke
				(width 0)
				(type default)
			)
			(fill no)
			(layer "F.CrtYd")
		)
		(fp_poly
			(pts
				(xy 1.0922 -2.3114) (xy 1.0922 2.3114) (xy -1.0922 2.3114) (xy -1.0922 -2.3114)
			)
			(stroke
				(width 0)
				(type default)
			)
			(fill no)
			(layer "F.Fab")
		)
		(pad "1" smd rect
			(at 0 -1.397 180)
			(size 1.651 1.27)
			(layers "F.Cu" "F.Mask" "F.Paste")
			(net "P12V_HDD0")
		)
		(pad "2" smd rect
			(at 0 1.397 180)
			(size 1.651 1.27)
			(layers "F.Cu" "F.Mask" "F.Paste")
			(net "GND")
		)
	)
	(footprint ""
		(layer "F.Cu")
		(at 39.572946 -137.1727 90)
		(property "Reference" "R314"
			(at 0 0 90)
			(layer "F.SilkS")
			(hide yes)
			(effects
				(font
					(size 1.27 1.27)
				)
			)
		)
		(property "Value" "0R2J-2-GP"
			(at 0.064008 -3.993896 90)
			(unlocked yes)
			(layer "F.Fab")
			(hide yes)
			(effects
				(font
					(size 1.016 1.016)
					(thickness 0.1524)
				)
			)
		)
		(property "Device Type" "R402H16"
			(at 0.064008 -5.517896 90)
			(unlocked yes)
			(layer "F.Fab")
			(hide yes)
			(effects
				(font
					(size 1.016 1.016)
					(thickness 0.1524)
				)
			)
		)
		(duplicate_pad_numbers_are_jumpers no)
		(fp_line
			(start 0.508 -0.9398)
			(end -0.508 -0.9398)
			(stroke
				(width 0.1524)
				(type default)
			)
			(layer "F.SilkS")
		)
		(fp_line
			(start -0.508 -0.9398)
			(end -0.508 0.9398)
			(stroke
				(width 0.1524)
				(type default)
			)
			(layer "F.SilkS")
		)
		(fp_rect
			(start -0.508 0.9398)
			(end 0.508 -0.9398)
			(stroke
				(width 0)
				(type default)
			)
			(fill no)
			(layer "F.CrtYd")
		)
		(fp_rect
			(start -0.508 0.9398)
			(end 0.508 -0.9398)
			(stroke
				(width 0)
				(type default)
			)
			(fill no)
			(layer "F.Fab")
		)
		(pad "1" smd custom
			(at 0 -0.4445 90)
			(size 0.1397 0.1397)
			(layers "F.Cu" "F.Mask" "F.Paste")
			(net "I2C_B_SDA")
			(options
				(clearance outline)
				(anchor circle)
			)
			(primitives
				(gr_poly
					(pts
						(arc
							(start -0.1778 -0.2794)
							(mid -0.249642 -0.249642)
							(end -0.2794 -0.1778)
						)
						(arc
							(start -0.2794 0.1778)
							(mid -0.249642 0.249642)
							(end -0.1778 0.2794)
						)
						(arc
							(start 0.1778 0.2794)
							(mid 0.249642 0.249642)
							(end 0.2794 0.1778)
						)
						(arc
							(start 0.2794 -0.1778)
							(mid 0.249642 -0.249642)
							(end 0.1778 -0.2794)
						)
					)
					(width 0)
					(fill yes)
				)
			)
		)
		(pad "2" smd custom
			(at 0 0.4445 90)
			(size 0.1397 0.1397)
			(layers "F.Cu" "F.Mask" "F.Paste")
			(net "TMP2_SDA")
			(options
				(clearance outline)
				(anchor circle)
			)
			(primitives
				(gr_poly
					(pts
						(arc
							(start -0.1778 -0.2794)
							(mid -0.249642 -0.249642)
							(end -0.2794 -0.1778)
						)
						(arc
							(start -0.2794 0.1778)
							(mid -0.249642 0.249642)
							(end -0.1778 0.2794)
						)
						(arc
							(start 0.1778 0.2794)
							(mid 0.249642 0.249642)
							(end 0.2794 0.1778)
						)
						(arc
							(start 0.2794 -0.1778)
							(mid 0.249642 -0.249642)
							(end 0.1778 -0.2794)
						)
					)
					(width 0)
					(fill yes)
				)
			)
		)
	)
	(footprint ""
		(layer "F.Cu")
		(at 207.264 -277.495)
		(property "Reference" "C366"
			(at 0 0 0)
			(layer "F.SilkS")
			(hide yes)
			(effects
				(font
					(size 1.27 1.27)
				)
			)
		)
		(property "Value" "SCD033U25V2KX-GP"
			(at 1.1811 -2.7051 0)
			(unlocked yes)
			(layer "F.Fab")
			(hide yes)
			(effects
				(font
					(size 1.016 1.016)
					(thickness 0.1524)
				)
			)
		)
		(property "Device Type" "C402H22"
			(at 1.1811 -4.2291 0)
			(unlocked yes)
			(layer "F.Fab")
			(hide yes)
			(effects
				(font
					(size 1.016 1.016)
					(thickness 0.1524)
				)
			)
		)
		(duplicate_pad_numbers_are_jumpers no)
		(fp_rect
			(start -0.4318 0.9525)
			(end 0.4318 -0.9525)
			(stroke
				(width 0)
				(type default)
			)
			(fill no)
			(layer "F.CrtYd")
		)
		(fp_rect
			(start -0.4318 0.9525)
			(end 0.4318 -0.9525)
			(stroke
				(width 0)
				(type default)
			)
			(fill no)
			(layer "F.Fab")
		)
		(pad "1" smd custom
			(at 0 -0.4445)
			(size 0.1524 0.1524)
			(layers "F.Cu" "F.Mask" "F.Paste")
			(net "SW_HDD2_P")
			(options
				(clearance outline)
				(anchor circle)
			)
			(primitives
				(gr_poly
					(pts
						(arc
							(start 0.3048 -0.2032)
							(mid 0.275042 -0.275042)
							(end 0.2032 -0.3048)
						)
						(arc
							(start -0.2032 -0.3048)
							(mid -0.275042 -0.275042)
							(end -0.3048 -0.2032)
						)
						(arc
							(start -0.3048 0.2032)
							(mid -0.275042 0.275042)
							(end -0.2032 0.3048)
						)
						(arc
							(start 0.2032 0.3048)
							(mid 0.275042 0.275042)
							(end 0.3048 0.2032)
						)
					)
					(width 0)
					(fill yes)
				)
			)
		)
		(pad "2" smd custom
			(at 0 0.4445)
			(size 0.1524 0.1524)
			(layers "F.Cu" "F.Mask" "F.Paste")
			(net "GND")
			(options
				(clearance outline)
				(anchor circle)
			)
			(primitives
				(gr_poly
					(pts
						(arc
							(start 0.3048 -0.2032)
							(mid 0.275042 -0.275042)
							(end 0.2032 -0.3048)
						)
						(arc
							(start -0.2032 -0.3048)
							(mid -0.275042 -0.275042)
							(end -0.3048 -0.2032)
						)
						(arc
							(start -0.3048 0.2032)
							(mid -0.275042 0.275042)
							(end -0.2032 0.3048)
						)
						(arc
							(start 0.2032 0.3048)
							(mid 0.275042 0.275042)
							(end 0.3048 0.2032)
						)
					)
					(width 0)
					(fill yes)
				)
			)
		)
	)
	(footprint ""
		(layer "F.Cu")
		(at 46.964346 -142.0622 -90)
		(property "Reference" "R498"
			(at 0 0 270)
			(layer "F.SilkS")
			(hide yes)
			(effects
				(font
					(size 1.27 1.27)
				)
			)
		)
		(property "Value" "1KR2F-3-GP"
			(at 0.064008 -3.993896 270)
			(unlocked yes)
			(layer "F.Fab")
			(hide yes)
			(effects
				(font
					(size 1.016 1.016)
					(thickness 0.1524)
				)
			)
		)
		(property "Device Type" "R402H16"
			(at 0.064008 -5.517896 270)
			(unlocked yes)
			(layer "F.Fab")
			(hide yes)
			(effects
				(font
					(size 1.016 1.016)
					(thickness 0.1524)
				)
			)
		)
		(duplicate_pad_numbers_are_jumpers no)
		(fp_line
			(start -0.508 -0.9398)
			(end -0.508 0.9398)
			(stroke
				(width 0.1524)
				(type default)
			)
			(layer "F.SilkS")
		)
		(fp_line
			(start 0.508 -0.9398)
			(end -0.508 -0.9398)
			(stroke
				(width 0.1524)
				(type default)
			)
			(layer "F.SilkS")
		)
		(fp_rect
			(start -0.508 0.9398)
			(end 0.508 -0.9398)
			(stroke
				(width 0)
				(type default)
			)
			(fill no)
			(layer "F.CrtYd")
		)
		(fp_rect
			(start -0.508 0.9398)
			(end 0.508 -0.9398)
			(stroke
				(width 0)
				(type default)
			)
			(fill no)
			(layer "F.Fab")
		)
		(pad "1" smd custom
			(at 0 -0.4445 270)
			(size 0.1397 0.1397)
			(layers "F.Cu" "F.Mask" "F.Paste")
			(net "FLT_HDD8_B")
			(options
				(clearance outline)
				(anchor circle)
			)
			(primitives
				(gr_poly
					(pts
						(arc
							(start -0.1778 -0.2794)
							(mid -0.249642 -0.249642)
							(end -0.2794 -0.1778)
						)
						(arc
							(start -0.2794 0.1778)
							(mid -0.249642 0.249642)
							(end -0.1778 0.2794)
						)
						(arc
							(start 0.1778 0.2794)
							(mid 0.249642 0.249642)
							(end 0.2794 0.1778)
						)
						(arc
							(start 0.2794 -0.1778)
							(mid 0.249642 -0.249642)
							(end 0.1778 -0.2794)
						)
					)
					(width 0)
					(fill yes)
				)
			)
		)
		(pad "2" smd custom
			(at 0 0.4445 270)
			(size 0.1397 0.1397)
			(layers "F.Cu" "F.Mask" "F.Paste")
			(net "FLT_HDD8_DRIVE")
			(options
				(clearance outline)
				(anchor circle)
			)
			(primitives
				(gr_poly
					(pts
						(arc
							(start -0.1778 -0.2794)
							(mid -0.249642 -0.249642)
							(end -0.2794 -0.1778)
						)
						(arc
							(start -0.2794 0.1778)
							(mid -0.249642 0.249642)
							(end -0.1778 0.2794)
						)
						(arc
							(start 0.1778 0.2794)
							(mid 0.249642 0.249642)
							(end 0.2794 0.1778)
						)
						(arc
							(start 0.2794 -0.1778)
							(mid 0.249642 -0.249642)
							(end 0.1778 -0.2794)
						)
					)
					(width 0)
					(fill yes)
				)
			)
		)
	)
	(footprint ""
		(layer "F.Cu")
		(at 190.880746 -290.0807 180)
		(property "Reference" "R140"
			(at 0 0 180)
			(layer "F.SilkS")
			(hide yes)
			(effects
				(font
					(size 1.27 1.27)
				)
			)
		)
		(property "Value" "0R2J-2-GP"
			(at 0.064008 -3.993896 180)
			(unlocked yes)
			(layer "F.Fab")
			(hide yes)
			(effects
				(font
					(size 1.016 1.016)
					(thickness 0.1524)
				)
			)
		)
		(property "Device Type" "R402H16"
			(at 0.064008 -5.517896 180)
			(unlocked yes)
			(layer "F.Fab")
			(hide yes)
			(effects
				(font
					(size 1.016 1.016)
					(thickness 0.1524)
				)
			)
		)
		(duplicate_pad_numbers_are_jumpers no)
		(fp_line
			(start 0.508 -0.9398)
			(end -0.508 -0.9398)
			(stroke
				(width 0.1524)
				(type default)
			)
			(layer "F.SilkS")
		)
		(fp_line
			(start -0.508 -0.9398)
			(end -0.508 0.9398)
			(stroke
				(width 0.1524)
				(type default)
			)
			(layer "F.SilkS")
		)
		(fp_rect
			(start -0.508 0.9398)
			(end 0.508 -0.9398)
			(stroke
				(width 0)
				(type default)
			)
			(fill no)
			(layer "F.CrtYd")
		)
		(fp_rect
			(start -0.508 0.9398)
			(end 0.508 -0.9398)
			(stroke
				(width 0)
				(type default)
			)
			(fill no)
			(layer "F.Fab")
		)
		(pad "1" smd custom
			(at 0 -0.4445 180)
			(size 0.1397 0.1397)
			(layers "F.Cu" "F.Mask" "F.Paste")
			(net "SW_PWR_HDD2")
			(options
				(clearance outline)
				(anchor circle)
			)
			(primitives
				(gr_poly
					(pts
						(arc
							(start -0.1778 -0.2794)
							(mid -0.249642 -0.249642)
							(end -0.2794 -0.1778)
						)
						(arc
							(start -0.2794 0.1778)
							(mid -0.249642 0.249642)
							(end -0.1778 0.2794)
						)
						(arc
							(start 0.1778 0.2794)
							(mid 0.249642 0.249642)
							(end 0.2794 0.1778)
						)
						(arc
							(start 0.2794 -0.1778)
							(mid 0.249642 -0.249642)
							(end 0.1778 -0.2794)
						)
					)
					(width 0)
					(fill yes)
				)
			)
		)
		(pad "2" smd custom
			(at 0 0.4445 180)
			(size 0.1397 0.1397)
			(layers "F.Cu" "F.Mask" "F.Paste")
			(net "SW_PWR_R_HDD2")
			(options
				(clearance outline)
				(anchor circle)
			)
			(primitives
				(gr_poly
					(pts
						(arc
							(start -0.1778 -0.2794)
							(mid -0.249642 -0.249642)
							(end -0.2794 -0.1778)
						)
						(arc
							(start -0.2794 0.1778)
							(mid -0.249642 0.249642)
							(end -0.1778 0.2794)
						)
						(arc
							(start 0.1778 0.2794)
							(mid 0.249642 0.249642)
							(end 0.2794 0.1778)
						)
						(arc
							(start 0.2794 -0.1778)
							(mid 0.249642 -0.249642)
							(end 0.1778 -0.2794)
						)
					)
					(width 0)
					(fill yes)
				)
			)
		)
	)
	(footprint ""
		(layer "F.Cu")
		(at 35.941 -305.308 90)
		(property "Reference" "R574"
			(at 0 0 90)
			(layer "F.SilkS")
			(hide yes)
			(effects
				(font
					(size 1.27 1.27)
				)
			)
		)
		(property "Value" "300KR2F-GP"
			(at 0.064008 -3.993896 90)
			(unlocked yes)
			(layer "F.Fab")
			(hide yes)
			(effects
				(font
					(size 1.016 1.016)
					(thickness 0.1524)
				)
			)
		)
		(property "Device Type" "R402H16"
			(at 0.064008 -5.517896 90)
			(unlocked yes)
			(layer "F.Fab")
			(hide yes)
			(effects
				(font
					(size 1.016 1.016)
					(thickness 0.1524)
				)
			)
		)
		(duplicate_pad_numbers_are_jumpers no)
		(fp_line
			(start 0.508 -0.9398)
			(end -0.508 -0.9398)
			(stroke
				(width 0.1524)
				(type default)
			)
			(layer "F.SilkS")
		)
		(fp_line
			(start -0.508 -0.9398)
			(end -0.508 0.9398)
			(stroke
				(width 0.1524)
				(type default)
			)
			(layer "F.SilkS")
		)
		(fp_rect
			(start -0.508 0.9398)
			(end 0.508 -0.9398)
			(stroke
				(width 0)
				(type default)
			)
			(fill no)
			(layer "F.CrtYd")
		)
		(fp_rect
			(start -0.508 0.9398)
			(end 0.508 -0.9398)
			(stroke
				(width 0)
				(type default)
			)
			(fill no)
			(layer "F.Fab")
		)
		(pad "1" smd custom
			(at 0 -0.4445 90)
			(size 0.1397 0.1397)
			(layers "F.Cu" "F.Mask" "F.Paste")
			(net "SW_HDD11_N")
			(options
				(clearance outline)
				(anchor circle)
			)
			(primitives
				(gr_poly
					(pts
						(arc
							(start -0.1778 -0.2794)
							(mid -0.249642 -0.249642)
							(end -0.2794 -0.1778)
						)
						(arc
							(start -0.2794 0.1778)
							(mid -0.249642 0.249642)
							(end -0.1778 0.2794)
						)
						(arc
							(start 0.1778 0.2794)
							(mid 0.249642 0.249642)
							(end 0.2794 0.1778)
						)
						(arc
							(start 0.2794 -0.1778)
							(mid 0.249642 -0.249642)
							(end 0.1778 -0.2794)
						)
					)
					(width 0)
					(fill yes)
				)
			)
		)
		(pad "2" smd custom
			(at 0 0.4445 90)
			(size 0.1397 0.1397)
			(layers "F.Cu" "F.Mask" "F.Paste")
			(net "P12V")
			(options
				(clearance outline)
				(anchor circle)
			)
			(primitives
				(gr_poly
					(pts
						(arc
							(start -0.1778 -0.2794)
							(mid -0.249642 -0.249642)
							(end -0.2794 -0.1778)
						)
						(arc
							(start -0.2794 0.1778)
							(mid -0.249642 0.249642)
							(end -0.1778 0.2794)
						)
						(arc
							(start 0.1778 0.2794)
							(mid 0.249642 0.249642)
							(end 0.2794 0.1778)
						)
						(arc
							(start 0.2794 -0.1778)
							(mid 0.249642 -0.249642)
							(end 0.1778 -0.2794)
						)
					)
					(width 0)
					(fill yes)
				)
			)
		)
	)
	(footprint ""
		(layer "F.Cu")
		(at 202.864974 -494.891822 -90)
		(property "Reference" "R423"
			(at 0 0 270)
			(layer "F.SilkS")
			(hide yes)
			(effects
				(font
					(size 1.27 1.27)
				)
			)
		)
		(property "Value" "4K7R2J-2-GP"
			(at 0.064008 -3.993896 270)
			(unlocked yes)
			(layer "F.Fab")
			(hide yes)
			(effects
				(font
					(size 1.016 1.016)
					(thickness 0.1524)
				)
			)
		)
		(property "Device Type" "R402H16"
			(at 0.064008 -5.517896 270)
			(unlocked yes)
			(layer "F.Fab")
			(hide yes)
			(effects
				(font
					(size 1.016 1.016)
					(thickness 0.1524)
				)
			)
		)
		(duplicate_pad_numbers_are_jumpers no)
		(fp_line
			(start -0.508 -0.9398)
			(end -0.508 0.9398)
			(stroke
				(width 0.1524)
				(type default)
			)
			(layer "F.SilkS")
		)
		(fp_line
			(start 0.508 -0.9398)
			(end -0.508 -0.9398)
			(stroke
				(width 0.1524)
				(type default)
			)
			(layer "F.SilkS")
		)
		(fp_rect
			(start -0.508 0.9398)
			(end 0.508 -0.9398)
			(stroke
				(width 0)
				(type default)
			)
			(fill no)
			(layer "F.CrtYd")
		)
		(fp_rect
			(start -0.508 0.9398)
			(end 0.508 -0.9398)
			(stroke
				(width 0)
				(type default)
			)
			(fill no)
			(layer "F.Fab")
		)
		(pad "1" smd custom
			(at 0 -0.4445 270)
			(size 0.1397 0.1397)
			(layers "F.Cu" "F.Mask" "F.Paste")
			(net "P3V3")
			(options
				(clearance outline)
				(anchor circle)
			)
			(primitives
				(gr_poly
					(pts
						(arc
							(start -0.1778 -0.2794)
							(mid -0.249642 -0.249642)
							(end -0.2794 -0.1778)
						)
						(arc
							(start -0.2794 0.1778)
							(mid -0.249642 0.249642)
							(end -0.1778 0.2794)
						)
						(arc
							(start 0.1778 0.2794)
							(mid 0.249642 0.249642)
							(end 0.2794 0.1778)
						)
						(arc
							(start 0.2794 -0.1778)
							(mid 0.249642 -0.249642)
							(end 0.1778 -0.2794)
						)
					)
					(width 0)
					(fill yes)
				)
			)
		)
		(pad "2" smd custom
			(at 0 0.4445 270)
			(size 0.1397 0.1397)
			(layers "F.Cu" "F.Mask" "F.Paste")
			(net "SAS2X28_A_HDD0_FLT")
			(options
				(clearance outline)
				(anchor circle)
			)
			(primitives
				(gr_poly
					(pts
						(arc
							(start -0.1778 -0.2794)
							(mid -0.249642 -0.249642)
							(end -0.2794 -0.1778)
						)
						(arc
							(start -0.2794 0.1778)
							(mid -0.249642 0.249642)
							(end -0.1778 0.2794)
						)
						(arc
							(start 0.1778 0.2794)
							(mid 0.249642 0.249642)
							(end 0.2794 0.1778)
						)
						(arc
							(start 0.2794 -0.1778)
							(mid 0.249642 -0.249642)
							(end 0.1778 -0.2794)
						)
					)
					(width 0)
					(fill yes)
				)
			)
		)
	)
)
